# S9S_MB_2U (Grand Teton) — schematic netlist excerpt (pin names and nets, part order shuffled) for the footprints in the layout excerpt that follows; sources: Cadence DE-HDL packaged netlist, KiCad conversion of 03242023_DA0F0TMBIJ0_F0T_Motherboard_J_brd_V01_OCP.brd

C419  Q_CAP  22UF 4V 20% X6S  pkg C0402  page 74 : A = PVCCFA_EHV_CPU0 ; B = GND
R2360  Q_RES  0 5% CHIP  pkg 0402LF  page 263 : A = PWRGD_P1V8_PCH_AUX_R ; B = PWRGD_P1V8_PCH_AUX

(kicad_pcb
	(version 20260206)
	(generator "pcbnew")
	(generator_version "10.0")
	(general
		(thickness 1.6)
		(legacy_teardrops no)
	)
	(paper "A4")
	(title_block
		(title "03242023_DA0F0TMBIJ0_F0T_Motherboard_J_brd_V01_OCP.brd")
		(comment 1 "Grand Teton / footprints 3090-3091 of 6105")
	)
	(layers
		(0 "F.Cu" signal "TOP")
		(4 "In1.Cu" signal "GND")
		(6 "In2.Cu" signal "IN1")
		(8 "In3.Cu" signal "GND1")
		(10 "In4.Cu" signal "IN2")
		(12 "In5.Cu" signal "GND2")
		(14 "In6.Cu" signal "IN3")
		(16 "In7.Cu" signal "GND3")
		(18 "In8.Cu" signal "VCC")
		(20 "In9.Cu" signal "VCC1")
		(22 "In10.Cu" signal "GND4")
		(24 "In11.Cu" signal "IN4")
		(26 "In12.Cu" signal "GND5")
		(28 "In13.Cu" signal "IN5")
		(30 "In14.Cu" signal "GND6")
		(32 "In15.Cu" signal "IN6")
		(34 "In16.Cu" signal "GND7")
		(2 "B.Cu" signal "BOTTOM")
		(9 "F.Adhes" user "F.Adhesive")
		(11 "B.Adhes" user "B.Adhesive")
		(13 "F.Paste" user "Package Geometry/Pastemask Top")
		(15 "B.Paste" user "Package Geometry/Pastemask Bottom")
		(5 "F.SilkS" user "Ref Des/Silkscreen Top")
		(7 "B.SilkS" user "Ref Des/Silkscreen Bottom")
		(1 "F.Mask" user "Board Geometry/Soldermask Top")
		(3 "B.Mask" user "Board Geometry/Soldermask Bottom")
		(17 "Dwgs.User" user "User.Drawings")
		(19 "Cmts.User" user "User.Comments")
		(21 "Eco1.User" user "User.Eco1")
		(23 "Eco2.User" user "User.Eco2")
		(25 "Edge.Cuts" user "Board Geometry/Outline")
		(27 "Margin" user)
		(31 "F.CrtYd" user "Package Geometry/Place Bound Top")
		(29 "B.CrtYd" user "Package Geometry/Place Bound Bottom")
		(35 "F.Fab" user "Ref Des/Assembly Top")
		(33 "B.Fab" user "Ref Des/Assembly Bottom")
	)
	(footprint ""
		(layer "F.Cu")
		(at 385.637532 -72.378824)
		(property "Reference" "R2360"
			(at 0 0 0)
			(layer "F.SilkS")
			(hide yes)
			(effects
				(font
					(size 1.27 1.27)
				)
			)
		)
		(property "Value" ""
			(at 0 0 0)
			(layer "F.Fab")
			(effects
				(font
					(size 1.27 1.27)
				)
			)
		)
		(duplicate_pad_numbers_are_jumpers no)
		(fp_line
			(start -0.7874 -0.4064)
			(end 0.7874 -0.4064)
			(stroke
				(width 0.1524)
				(type default)
			)
			(layer "F.SilkS")
		)
		(fp_line
			(start -0.7874 0.4064)
			(end -0.7874 -0.4064)
			(stroke
				(width 0.1524)
				(type default)
			)
			(layer "F.SilkS")
		)
		(fp_line
			(start 0.7874 -0.4064)
			(end 0.7874 0.4064)
			(stroke
				(width 0.1524)
				(type default)
			)
			(layer "F.SilkS")
		)
		(fp_line
			(start 0.7874 0.4064)
			(end -0.7874 0.4064)
			(stroke
				(width 0.1524)
				(type default)
			)
			(layer "F.SilkS")
		)
		(fp_line
			(start -0.67945 -0.305054)
			(end -0.12065 -0.305054)
			(stroke
				(width 0.1)
				(type default)
			)
			(layer "F.Fab")
		)
		(fp_line
			(start -0.67945 0.3048)
			(end -0.67945 -0.305054)
			(stroke
				(width 0.1)
				(type default)
			)
			(layer "F.Fab")
		)
		(fp_line
			(start -0.12065 -0.305054)
			(end -0.12065 -0.2794)
			(stroke
				(width 0.1)
				(type default)
			)
			(layer "F.Fab")
		)
		(fp_line
			(start -0.12065 -0.2794)
			(end 0.12065 -0.2794)
			(stroke
				(width 0.1)
				(type default)
			)
			(layer "F.Fab")
		)
		(fp_line
			(start -0.12065 0.2794)
			(end -0.12065 0.3048)
			(stroke
				(width 0.1)
				(type default)
			)
			(layer "F.Fab")
		)
		(fp_line
			(start -0.12065 0.3048)
			(end -0.67945 0.3048)
			(stroke
				(width 0.1)
				(type default)
			)
			(layer "F.Fab")
		)
		(fp_line
			(start 0.120396 0.2794)
			(end -0.12065 0.2794)
			(stroke
				(width 0.1)
				(type default)
			)
			(layer "F.Fab")
		)
		(fp_line
			(start 0.120396 0.3048)
			(end 0.120396 0.2794)
			(stroke
				(width 0.1)
				(type default)
			)
			(layer "F.Fab")
		)
		(fp_line
			(start 0.12065 -0.3048)
			(end 0.67945 -0.3048)
			(stroke
				(width 0.1)
				(type default)
			)
			(layer "F.Fab")
		)
		(fp_line
			(start 0.12065 -0.2794)
			(end 0.12065 -0.3048)
			(stroke
				(width 0.1)
				(type default)
			)
			(layer "F.Fab")
		)
		(fp_line
			(start 0.67945 -0.3048)
			(end 0.67945 0.3048)
			(stroke
				(width 0.1)
				(type default)
			)
			(layer "F.Fab")
		)
		(fp_line
			(start 0.67945 0.3048)
			(end 0.120396 0.3048)
			(stroke
				(width 0.1)
				(type default)
			)
			(layer "F.Fab")
		)
		(pad "1" smd circle
			(at -0.40005 0)
			(size 0 0)
			(layers "F.Cu" "F.Mask" "F.Paste")
			(net "PWRGD_P1V8_PCH_AUX_R")
		)
		(pad "2" smd circle
			(at 0.40005 0)
			(size 0 0)
			(layers "F.Cu" "F.Mask" "F.Paste")
			(net "PWRGD_P1V8_PCH_AUX")
		)
	)
	(footprint ""
		(layer "F.Cu")
		(at 353.245928 -258.726686 90)
		(property "Reference" "C419"
			(at 0 0 90)
			(layer "F.SilkS")
			(hide yes)
			(effects
				(font
					(size 1.27 1.27)
				)
			)
		)
		(property "Value" ""
			(at 0 0 90)
			(layer "F.Fab")
			(effects
				(font
					(size 1.27 1.27)
				)
			)
		)
		(duplicate_pad_numbers_are_jumpers no)
		(fp_line
			(start 0.7874 -0.4064)
			(end 0.7874 0.4064)
			(stroke
				(width 0.1524)
				(type default)
			)
			(layer "F.SilkS")
		)
		(fp_line
			(start -0.7874 -0.4064)
			(end 0.7874 -0.4064)
			(stroke
				(width 0.1524)
				(type default)
			)
			(layer "F.SilkS")
		)
		(fp_line
			(start 0.7874 0.4064)
			(end -0.7874 0.4064)
			(stroke
				(width 0.1524)
				(type default)
			)
			(layer "F.SilkS")
		)
		(fp_line
			(start -0.7874 0.4064)
			(end -0.7874 -0.4064)
			(stroke
				(width 0.1524)
				(type default)
			)
			(layer "F.SilkS")
		)
		(fp_line
			(start -0.12065 -0.305054)
			(end -0.12065 -0.2794)
			(stroke
				(width 0.1)
				(type default)
			)
			(layer "F.Fab")
		)
		(fp_line
			(start -0.67945 -0.305054)
			(end -0.12065 -0.305054)
			(stroke
				(width 0.1)
				(type default)
			)
			(layer "F.Fab")
		)
		(fp_line
			(start 0.67945 -0.3048)
			(end 0.67945 0.3048)
			(stroke
				(width 0.1)
				(type default)
			)
			(layer "F.Fab")
		)
		(fp_line
			(start 0.12065 -0.3048)
			(end 0.67945 -0.3048)
			(stroke
				(width 0.1)
				(type default)
			)
			(layer "F.Fab")
		)
		(fp_line
			(start 0.12065 -0.2794)
			(end 0.12065 -0.3048)
			(stroke
				(width 0.1)
				(type default)
			)
			(layer "F.Fab")
		)
		(fp_line
			(start -0.12065 -0.2794)
			(end 0.12065 -0.2794)
			(stroke
				(width 0.1)
				(type default)
			)
			(layer "F.Fab")
		)
		(fp_line
			(start 0.120396 0.2794)
			(end -0.12065 0.2794)
			(stroke
				(width 0.1)
				(type default)
			)
			(layer "F.Fab")
		)
		(fp_line
			(start -0.12065 0.2794)
			(end -0.12065 0.3048)
			(stroke
				(width 0.1)
				(type default)
			)
			(layer "F.Fab")
		)
		(fp_line
			(start 0.67945 0.3048)
			(end 0.120396 0.3048)
			(stroke
				(width 0.1)
				(type default)
			)
			(layer "F.Fab")
		)
		(fp_line
			(start 0.120396 0.3048)
			(end 0.120396 0.2794)
			(stroke
				(width 0.1)
				(type default)
			)
			(layer "F.Fab")
		)
		(fp_line
			(start -0.12065 0.3048)
			(end -0.67945 0.3048)
			(stroke
				(width 0.1)
				(type default)
			)
			(layer "F.Fab")
		)
		(fp_line
			(start -0.67945 0.3048)
			(end -0.67945 -0.305054)
			(stroke
				(width 0.1)
				(type default)
			)
			(layer "F.Fab")
		)
		(pad "1" smd circle
			(at -0.40005 0 90)
			(size 0 0)
			(layers "F.Cu" "F.Mask" "F.Paste")
			(net "PVCCFA_EHV_CPU0")
		)
		(pad "2" smd circle
			(at 0.40005 0 90)
			(size 0 0)
			(layers "F.Cu" "F.Mask" "F.Paste")
			(net "GND")
		)
	)
)
